FILE_TYPE = MACRO_DRAWING;
SET COLOR_WIRE YELLOW;
SET COLOR_PROP MONO;
SET COLOR_DOT WHITE;
SET COLOR_ARC YELLOW;
SET COLOR_BODY GREEN;
SET COLOR_NOTE MONO;
SET PROP_DISPLAY VALUE;
SET PAGE_NUMBER P17;
FORCEADD INTEL_CORP_BPAGE..1
(0 0);
FORCEPROP 1 LAST CUSTOM_TXT_CDS <CURRENT_DESIGN_SHEET> OF <TOTAL_DESIGN_SHEETS>
J 0
(-500 25);
PAINT GREEN (-500 25);
FORCEPROP 1 LAST CUSTOM_TXT_CDS <CON_LAST_MODIFIED>
J 0
(-1925 350);
PAINT GREEN (-1925 350);
FORCEPROP 2 LAST CUSTOM_TXT_CDS <XR_PAGE_TITLE>
J 0
(-7890 5250);
DISPLAY 0.638298 (-7890 5250);
PAINT PINK (-7890 5250);
DISPLAY INVISIBLE (-7890 5250);
FORCEPROP 1 LAST SCH_ADDRESS3 Santa Clara, CA 95052-8119
J 0
(-3975 25);
DISPLAY 0.617021 (-3975 25);
PAINT GREEN (-3975 25);
FORCEPROP 1 LAST SCH_ADDRESS2 P.O. BOX 58119
J 0
(-3975 75);
DISPLAY 0.617021 (-3975 75);
PAINT GREEN (-3975 75);
FORCEPROP 1 LAST SCH_ADDRESS1 2200 Mission College Blvd.
J 0
(-3975 125);
DISPLAY 0.617021 (-3975 125);
PAINT GREEN (-3975 125);
FORCEPROP 1 LAST SCH_NUMBER H4694802
J 0
(-1300 150);
DISPLAY 1.212766 (-1300 150);
PAINT YELLOW (-1300 150);
FORCEPROP 1 LAST SCH_DEPT BESD
J 1
(-4450 100);
DISPLAY 1.212766 (-4450 100);
PAINT YELLOW (-4450 100);
FORCEPROP 1 LAST SCH_REV 2.420
J 0
(-250 150);
DISPLAY 0.978723 (-250 150);
PAINT YELLOW (-250 150);
FORCEPROP 1 LAST SCH_TITLE POWER/RESET TIMING G3 > S5 > S0 > S5
J 0
(-7950 50);
DISPLAY 1.212766 (-7950 50);
PAINT ORANGE (-7950 50);
FORCEPROP 2 LAST PAGE_BORDER TRUE
J 0
(-7890 5250);
DISPLAY 0.638298 (-7890 5250);
PAINT PINK (-7890 5250);
DISPLAY INVISIBLE (-7890 5250);
FORCEPROP 2 LAST CDS_LIB mstr_symbols
J 0
(0 0);
PAINT ORANGE (0 0);
DISPLAY INVISIBLE (0 0);
FORCEPROP 1 LAST COMMENT_BODY TRUE
J 0
(12 12);
DISPLAY 0.468085 (12 12);
PAINT GREEN (12 12);
DISPLAY INVISIBLE (12 12);
FORCEPROP 1 LAST CDS_CON_LAST_MODIFIED Tue Dec 01 11:47:59 2015
J 0
(-1425 325);
PAINT ORANGE (-1425 325);
DISPLAY INVISIBLE (-1425 325);
FORCEPROP 2 LAST CDS_XR_PAGE_TITLE CR-17 : @BASEBOARD_FAB2_LIB.BASEBOARD_FAB2(SCH_1):PAGE17
J 0
(-7890 5250);
DISPLAY 0.638298 (-7890 5250);
PAINT PINK (-7890 5250);
DISPLAY INVISIBLE (-7890 5250);
FORCENOTE
$CDS_IMAGE|017_POWER SEQUENCE.jpg|5277|4250
(-4225 2650) 0;
DISPLAY CENTER (-4225 2650);
PAINT MONO (-4225 2650);
QUIT
